# S9S_MB_2U (Grand Teton) — schematic netlist excerpt (pin names and nets, part order shuffled) for the footprints in the layout excerpt that follows; sources: Cadence DE-HDL packaged netlist, KiCad conversion of 03242023_DA0F0TMBIJ0_F0T_Motherboard_J_brd_V01_OCP.brd

J75  PICOPROBE_BXA  DELTA-L 4.0 EMPTY  pkg TRIANG_LAUNCH_3PXB  page 308
  \1_p\  = DELTA_L_85_10INCH_TOP_DP
  \2_n\  = DELTA_L_85_10INCH_TOP_DN
  \3_g\  = DELTA_L_GND_1

(kicad_pcb
	(version 20260206)
	(generator "pcbnew")
	(generator_version "10.0")
	(general
		(thickness 1.6)
		(legacy_teardrops no)
	)
	(paper "A4")
	(title_block
		(title "03242023_DA0F0TMBIJ0_F0T_Motherboard_J_brd_V01_OCP.brd")
		(comment 1 "Grand Teton / footprints 4126-4126 of 6105")
	)
	(layers
		(0 "F.Cu" signal "TOP")
		(4 "In1.Cu" signal "GND")
		(6 "In2.Cu" signal "IN1")
		(8 "In3.Cu" signal "GND1")
		(10 "In4.Cu" signal "IN2")
		(12 "In5.Cu" signal "GND2")
		(14 "In6.Cu" signal "IN3")
		(16 "In7.Cu" signal "GND3")
		(18 "In8.Cu" signal "VCC")
		(20 "In9.Cu" signal "VCC1")
		(22 "In10.Cu" signal "GND4")
		(24 "In11.Cu" signal "IN4")
		(26 "In12.Cu" signal "GND5")
		(28 "In13.Cu" signal "IN5")
		(30 "In14.Cu" signal "GND6")
		(32 "In15.Cu" signal "IN6")
		(34 "In16.Cu" signal "GND7")
		(2 "B.Cu" signal "BOTTOM")
		(9 "F.Adhes" user "F.Adhesive")
		(11 "B.Adhes" user "B.Adhesive")
		(13 "F.Paste" user "Package Geometry/Pastemask Top")
		(15 "B.Paste" user "Package Geometry/Pastemask Bottom")
		(5 "F.SilkS" user "Ref Des/Silkscreen Top")
		(7 "B.SilkS" user "Ref Des/Silkscreen Bottom")
		(1 "F.Mask" user "Board Geometry/Soldermask Top")
		(3 "B.Mask" user "Board Geometry/Soldermask Bottom")
		(17 "Dwgs.User" user "User.Drawings")
		(19 "Cmts.User" user "User.Comments")
		(21 "Eco1.User" user "User.Eco1")
		(23 "Eco2.User" user "User.Eco2")
		(25 "Edge.Cuts" user "Board Geometry/Outline")
		(27 "Margin" user)
		(31 "F.CrtYd" user "Package Geometry/Place Bound Top")
		(29 "B.CrtYd" user "Package Geometry/Place Bound Bottom")
		(35 "F.Fab" user "Ref Des/Assembly Top")
		(33 "B.Fab" user "Ref Des/Assembly Bottom")
	)
	(footprint ""
		(layer "F.Cu")
		(at 260.731508 -4.696206)
		(property "Reference" "J75"
			(at -4.164838 1.013206 90)
			(unlocked yes)
			(layer "F.SilkS")
			(effects
				(font
					(size 0.7874 0.5842)
					(thickness 0.1524)
				)
				(justify left)
			)
		)
		(property "Value" ""
			(at 0 0 0)
			(layer "F.Fab")
			(effects
				(font
					(size 1.27 1.27)
				)
			)
		)
		(duplicate_pad_numbers_are_jumpers no)
		(fp_line
			(start -1.2192 -2.1082)
			(end 1.2192 -2.1082)
			(stroke
				(width 0.1524)
				(type default)
			)
			(layer "F.SilkS")
		)
		(fp_line
			(start -1.2192 2.1082)
			(end -1.2192 -2.1082)
			(stroke
				(width 0.1524)
				(type default)
			)
			(layer "F.SilkS")
		)
		(fp_line
			(start 1.2192 -2.1082)
			(end 1.2192 2.1082)
			(stroke
				(width 0.1524)
				(type default)
			)
			(layer "F.SilkS")
		)
		(fp_line
			(start 1.2192 2.1082)
			(end -1.2192 2.1082)
			(stroke
				(width 0.1524)
				(type default)
			)
			(layer "F.SilkS")
		)
		(pad "" np_thru_hole circle
			(at -2.8829 -1.27 270)
			(size 1.0414 1.0414)
			(drill 1.0414)
			(layers "*.Cu" "*.Mask")
			(clearance 0.381)
			(thermal_gap 0.381)
		)
		(pad "" np_thru_hole circle
			(at -2.8829 1.27 270)
			(size 1.0414 1.0414)
			(drill 1.0414)
			(layers "*.Cu" "*.Mask")
			(clearance 0.381)
			(thermal_gap 0.381)
		)
		(pad "" np_thru_hole circle
			(at 3.4671 -1.27 270)
			(size 1.0414 1.0414)
			(drill 1.0414)
			(layers "*.Cu" "*.Mask")
			(clearance 0.381)
			(thermal_gap 0.381)
		)
		(pad "" np_thru_hole circle
			(at 3.4671 1.27 270)
			(size 1.0414 1.0414)
			(drill 1.0414)
			(layers "*.Cu" "*.Mask")
			(clearance 0.381)
			(thermal_gap 0.381)
		)
		(pad "1" smd rect
			(at 0.8255 -0.249936 270)
			(size 0.3048 0.508)
			(layers "F.Cu" "F.Mask" "F.Paste")
			(net "DELTA_L_85_10INCH_TOP_DP")
		)
		(pad "2" smd rect
			(at 0.8255 0.249936 270)
			(size 0.3048 0.508)
			(layers "F.Cu" "F.Mask" "F.Paste")
			(net "DELTA_L_85_10INCH_TOP_DN")
		)
		(pad "3" smd circle
			(at 0 0)
			(size 0 0)
			(layers "F.Cu" "F.Mask" "F.Paste")
			(net "DELTA_L_GND_1")
		)
		(zone
			(layer "F.Cu")
			(hatch none 0.5)
			(connect_pads
				(clearance 0)
			)
			(min_thickness 0.25)
			(keepout
				(tracks not_allowed)
				(vias allowed)
				(pads allowed)
				(copperpour not_allowed)
				(footprints allowed)
			)
			(placement
				(enabled no)
				(sheetname "")
			)
			(fill
				(thermal_gap 0.5)
				(thermal_bridge_width 0.5)
				(island_removal_mode 0)
			)
			(polygon
				(pts
					(xy 261.849108 -5.244846) (xy 261.849108 -5.149342) (xy 261.252208 -5.149342) (xy 261.252208 -4.742942)
					(xy 261.849108 -4.742942) (xy 261.849108 -4.64947) (xy 261.252208 -4.64947) (xy 261.252208 -4.24307)
					(xy 261.849108 -4.24307) (xy 261.849108 -4.147566) (xy 261.150608 -4.147566) (xy 261.150608 -5.244846)
				)
			)
		)
		(zone
			(layers "F.Cu" "B.Cu" "In1.Cu" "In2.Cu" "In3.Cu" "In4.Cu" "In5.Cu" "In6.Cu"
				"In7.Cu" "In8.Cu" "In9.Cu" "In10.Cu" "In11.Cu" "In12.Cu" "In13.Cu" "In14.Cu"
				"In15.Cu" "In16.Cu"
			)
			(hatch none 0.5)
			(connect_pads
				(clearance 0)
			)
			(min_thickness 0.25)
			(keepout
				(tracks not_allowed)
				(vias allowed)
				(pads allowed)
				(copperpour not_allowed)
				(footprints allowed)
			)
			(placement
				(enabled no)
				(sheetname "")
			)
			(fill
				(thermal_gap 0.5)
				(thermal_bridge_width 0.5)
				(island_removal_mode 0)
			)
			(polygon
				(pts
					(arc
						(start 258.775708 -5.966206)
						(mid 256.921508 -5.966206)
						(end 258.775708 -5.966206)
					)
				)
			)
		)
		(zone
			(layers "F.Cu" "B.Cu" "In1.Cu" "In2.Cu" "In3.Cu" "In4.Cu" "In5.Cu" "In6.Cu"
				"In7.Cu" "In8.Cu" "In9.Cu" "In10.Cu" "In11.Cu" "In12.Cu" "In13.Cu" "In14.Cu"
				"In15.Cu" "In16.Cu"
			)
			(hatch none 0.5)
			(connect_pads
				(clearance 0)
			)
			(min_thickness 0.25)
			(keepout
				(tracks not_allowed)
				(vias allowed)
				(pads allowed)
				(copperpour not_allowed)
				(footprints allowed)
			)
			(placement
				(enabled no)
				(sheetname "")
			)
			(fill
				(thermal_gap 0.5)
				(thermal_bridge_width 0.5)
				(island_removal_mode 0)
			)
			(polygon
				(pts
					(arc
						(start 258.775708 -3.426206)
						(mid 256.921508 -3.426206)
						(end 258.775708 -3.426206)
					)
				)
			)
		)
		(zone
			(layers "F.Cu" "B.Cu" "In1.Cu" "In2.Cu" "In3.Cu" "In4.Cu" "In5.Cu" "In6.Cu"
				"In7.Cu" "In8.Cu" "In9.Cu" "In10.Cu" "In11.Cu" "In12.Cu" "In13.Cu" "In14.Cu"
				"In15.Cu" "In16.Cu"
			)
			(hatch none 0.5)
			(connect_pads
				(clearance 0)
			)
			(min_thickness 0.25)
			(keepout
				(tracks not_allowed)
				(vias allowed)
				(pads allowed)
				(copperpour not_allowed)
				(footprints allowed)
			)
			(placement
				(enabled no)
				(sheetname "")
			)
			(fill
				(thermal_gap 0.5)
				(thermal_bridge_width 0.5)
				(island_removal_mode 0)
			)
			(polygon
				(pts
					(arc
						(start 265.125708 -5.966206)
						(mid 263.271508 -5.966206)
						(end 265.125708 -5.966206)
					)
				)
			)
		)
		(zone
			(layers "F.Cu" "B.Cu" "In1.Cu" "In2.Cu" "In3.Cu" "In4.Cu" "In5.Cu" "In6.Cu"
				"In7.Cu" "In8.Cu" "In9.Cu" "In10.Cu" "In11.Cu" "In12.Cu" "In13.Cu" "In14.Cu"
				"In15.Cu" "In16.Cu"
			)
			(hatch none 0.5)
			(connect_pads
				(clearance 0)
			)
			(min_thickness 0.25)
			(keepout
				(tracks not_allowed)
				(vias allowed)
				(pads allowed)
				(copperpour not_allowed)
				(footprints allowed)
			)
			(placement
				(enabled no)
				(sheetname "")
			)
			(fill
				(thermal_gap 0.5)
				(thermal_bridge_width 0.5)
				(island_removal_mode 0)
			)
			(polygon
				(pts
					(arc
						(start 265.125708 -3.426206)
						(mid 263.271508 -3.426206)
						(end 265.125708 -3.426206)
					)
				)
			)
		)
	)
)
